# BARRELEYE-G2-EXPANDER-EVT-HW-EBOM-X00-20161124-add_2nd_source_X06-20161207-Final.xls — Changelist (bom)
| BOM Change List Date:Wed Dec 07 16:08:48 GMT+08:00 2016 |  |  |  |  |  |  |  |  |  |
| New BOM file : BARRELEYE-G2-EXPANDER-EVT-HW-EBOM-X00-20161124-add 2nd source_X06-20161207-Final.xls |  |  |  |  |  |  |  |  |  |
| Old BOM file : BARRELEYE-G2-EXPANDER-EVT-HW-EBOM-X00-20161124-add 2nd source_X05-20161124.xls |  |  |  |  |  |  |  |  |  |
| ##### Add Parts |  |  |  |  |  |  |  |  |  |
| Item | Location | Qty | Foxconn P/N | Part Description | Manufacturer Full Name | Manufacturer P/N | RoHS | Sheet |  |
| ##### Remove Parts |  |  |  |  |  |  |  |  |  |
| Item | Location | Qty | Foxconn P/N | Part Description | Manufacturer Full Name | Manufacturer P/N | RoHS | Sheet |  |
| 1 | PSCC5 | 1 | 62010L800-015-G | CAP,1nF,+/-5%,NPO(C0G),50V,G,SMD0402 | MURATA ELEC. NORTH AMERICA | GRM1555C1H102J |  |  |  |
|  |  |  | 62010L800-026-G | CAP,1nF,+/-5%,NPO(C0G),50V,G,SMD0402 | SAMSUNG SEMICONDUCTOR | CL05C102JB5NNNC |  |  |  |
|  |  |  | 62010L800-012-G | CAP,1nF,+/-5%,NPO(C0G),50V,G,SMD0402 | WALSIN | 0402N102J500CT |  |  |  |
| 2 | PSCR4 | 1 | 61011HA00-017-G | RES,1 Ohm,+/-1%,1/16W,G,SMD0402 | KOA SPEER ELECTRONICS, INC. | RK73H1ETTP1R00F |  |  |  |
|  |  |  | 61011HA00-011-G | RES,1 Ohm,+/-1%,1/16W,G,SMD0402 | YAGEO | RC0402FR-071RL |  |  |  |
|  |  |  | 61011HA00-012-G | RES,1 Ohm,+/-1%,1/16W,G,SMD0402 | WALSIN | WR04W1R00FTL |  |  |  |
|  |  |  | 61011HA00-044-G | RES,1 Ohm,+/-1%,1/16W,G,SMD0402 | TA-I | RM04FTN1R00 |  |  |  |
|  |  |  | 61011HA00-029-G | RES,1 Ohm,+/-1%,1/16W,G,SMD0402 | VISHAY ENTER TECHNO LOGY.INC | CRCW04021R00FNED |  |  |  |
| ##### Change Parts |  |  |  |  |  |  |  |  |  |
| Item | Location | Qty | Foxconn P/N | Part Description | Manufacturer Full Name | Manufacturer P/N | RoHS | Sheet | Remark |
| 1 | C3,C6,C7,C25,C30,C39,C44,C49,C54,C61,C62,C69,C70,C77,C78,C85,C86,C93,C94,C101,C102,C109,C110,C117,C118,C125,C126,C133,C134,C141,C142,C149,C150 | 33 | 620106200-015-G | CAP,10nF,+/-10%,X7R,16V,G,SMD0402 | MURATA ELEC. NORTH AMERICA | GRM155R71C103KA01D |  | PWA BOM | In New BOM |
|  |  |  | 620106200-012-G | CAP,10nF,+/-10%,X7R,16V,G,SMD0402 | WALSIN | 0402B103K160CT |  | PWA BOM | In New BOM |
|  |  |  | 620106200-026-G | CAP,10nF,+/-10%,X7R,16V,G,SMD0402 | SAMSUNG SEMICONDUCTOR | CL05B103KO5NNNC |  | PWA BOM | In New BOM |
|  |  |  | 620106200-023-G | CAP,10nF,+/-10%,X7R,16V,G,SMD0402 | TAIYO ELECTRIC IND.CO.LTD | EMK105B7103KV-F |  | PWA BOM | In New BOM |
|  | C3,C6,C7,C25,C30,C39,C44,C49,C54,C61,C62,C69,C70,C77,C78,C85,C86,C93,C94,C101,C102,C109,C110,C117,C118,C125,C126,C133,C134,C141,C142,C149,C150 | 33 | 620106205-015-G | CAP,10nF,+/-10%,X7R,16V,G,SMD0402 | MURATA ELEC. NORTH AMERICA | GRM155R71C103KA01D |  | PWA BOM | In Old BOM |
|  |  |  | 620106200-012-G | CAP,10nF,+/-10%,X7R,16V,G,SMD0402 | WALSIN | 0402B103K160CT |  | PWA BOM | In Old BOM |
|  |  |  | 620106200-026-G | CAP,10nF,+/-10%,X7R,16V,G,SMD0402 | SAMSUNG SEMICONDUCTOR | CL05B103KO5NNNC |  | PWA BOM | In Old BOM |
|  |  |  | 620106200-023-G | CAP,10nF,+/-10%,X7R,16V,G,SMD0402 | TAIYO ELECTRIC IND.CO.LTD | EMK105B7103KV-F |  | PWA BOM | In Old BOM |
| ##### Change Revision |  |  |  |  |  |  |  |  |  |
| Sheet | REV OF BOM | CUSTOMER | CUSTOMER P/N | PWA PN | PWA DESCRIPTION | PWA REV | DATE | Remark |  |
| PWA BOM | X06 | Rackspace |  |  |  |  |  | In New BOM |  |
| PWA BOM | X05 | Rackspace |  |  |  |  |  | In Old BOM |  |
| OOOOOOOOOOOOOOOOOOOOOOOOOOOOOOOOOOOOOOOOOOOOOOOOOOOOOOOOOOOOOOOOOOOOOOOOOOOOOOOOOOOOOOOOOO | OOOOOOOOOOOOOOOOOOOOOOOOOOOOOOOOOOOOOOOOOOOOOOOOOOOOOOOOOOOOOOOOOOOOOOOOOOOOOOOOOOOOOOOOOO | OOOOOOOOOOOOOOOOOOOOOOOOOOOOOOOOOOOOOOOOOOOOOOOOOOOOOOOOOOOOOOOOOOOOOOOOOOOOOOOOOOOOOOOOOO | OOOOOOOOOOOOOOOOOOOOOOOOOOOOOOOOOOOOOOOOOOOOOOOOOOOOOOOOOOOOOOOOOOOOOOOOOOOOOOOOOOOOOOOOOO | OOOOOOOOOOOOOOOOOOOOOOOOOOOOOOOOOOOOOOOOOOOOOOOOOOOOOOOOOOOOOOOOOOOOOOOOOOOOOOOOOOOOOOOOOO | OOOOOOOOOOOOOOOOOOOOOOOOOOOOOOOOOOOOOOOOOOOOOOOOOOOOOOOOOOOOOOOOOOOOOOOOOOOOOOOOOOOOOOOOOO | OOOOOOOOOOOOOOOOOOOOOOOOOOOOOOOOOOOOOOOOOOOOOOOOOOOOOOOOOOOOOOOOOOOOOOOOOOOOOOOOOOOOOOOOOO | OOOOOOOOOOOOOOOOOOOOOOOOOOOOOOOOOOOOOOOOOOOOOOOOOOOOOOOOOOOOOOOOOOOOOOOOOOOOOOOOOOOOOOOOOO | OOOOOOOOOOOOOOOOOOOOOOOOOOOOOOOOOOOOOOOOOOOOOOOOOOOOOOOOOOOOOOOOOOOOOOOOOOOOOOOOOOOOOOOOOO | OOOOOOOOOOOOOOOOOOOOOOOOOOOOOOOOOOOOOOOOOOOOOOOOOOOOOOOOOOOOOOOOOOOOOOOOOOOOOOOOOOOOOOOOOO |
| Second Source Change |  |  |  |  |  |  |  |  |  |
| Item | Location | Change Type | Foxconn P/N | Part Description | Manufacturer Full Name | Manufacturer P/N | RoHS | Sheet |  |
| OOOOOOOOOOOOOOOOOOOOOOOOOOOOOOOOOOOOOOOOOOOOOOOOOOOOOOOOOOOOOOOOOOOOOOOOOOOOOOOOOOOOOOOOOO | OOOOOOOOOOOOOOOOOOOOOOOOOOOOOOOOOOOOOOOOOOOOOOOOOOOOOOOOOOOOOOOOOOOOOOOOOOOOOOOOOOOOOOOOOO | OOOOOOOOOOOOOOOOOOOOOOOOOOOOOOOOOOOOOOOOOOOOOOOOOOOOOOOOOOOOOOOOOOOOOOOOOOOOOOOOOOOOOOOOOO | OOOOOOOOOOOOOOOOOOOOOOOOOOOOOOOOOOOOOOOOOOOOOOOOOOOOOOOOOOOOOOOOOOOOOOOOOOOOOOOOOOOOOOOOOO | OOOOOOOOOOOOOOOOOOOOOOOOOOOOOOOOOOOOOOOOOOOOOOOOOOOOOOOOOOOOOOOOOOOOOOOOOOOOOOOOOOOOOOOOOO | OOOOOOOOOOOOOOOOOOOOOOOOOOOOOOOOOOOOOOOOOOOOOOOOOOOOOOOOOOOOOOOOOOOOOOOOOOOOOOOOOOOOOOOOOO | OOOOOOOOOOOOOOOOOOOOOOOOOOOOOOOOOOOOOOOOOOOOOOOOOOOOOOOOOOOOOOOOOOOOOOOOOOOOOOOOOOOOOOOOOO | OOOOOOOOOOOOOOOOOOOOOOOOOOOOOOOOOOOOOOOOOOOOOOOOOOOOOOOOOOOOOOOOOOOOOOOOOOOOOOOOOOOOOOOOOO | OOOOOOOOOOOOOOOOOOOOOOOOOOOOOOOOOOOOOOOOOOOOOOOOOOOOOOOOOOOOOOOOOOOOOOOOOOOOOOOOOOOOOOOOOO | OOOOOOOOOOOOOOOOOOOOOOOOOOOOOOOOOOOOOOOOOOOOOOOOOOOOOOOOOOOOOOOOOOOOOOOOOOOOOOOOOOOOOOOOOO |
| Master Materials Change |  |  |  |  |  |  |  |  |  |
| Item | Foxconn P/N | Orig._Usage | New_Usage | Part Description | Manufacturer Full Name | Manufacturer P/N | RoHS | Location | Sheet |
| 1 | 620106200-015-G | 0 | 33 | CAP,10nF,+/-10%,X7R,16V,G,SMD0402 | MURATA ELEC. NORTH AMERICA | GRM155R71C103KA01D |  | (+)C3,C6,C7,C25,C30,C39,C44,C49,C54,C61,C62,C69,C70,C77,C78,C85,C86,C93,C94,C101,C102,C109,C110,C117,C118,C125,C126,C133,C134,C141,C142,C149,C150 | PWA BOM |
|  | 620106200-012-G |  |  | CAP,10nF,+/-10%,X7R,16V,G,SMD0402 | WALSIN | 0402B103K160CT |  |  | PWA BOM |
|  | 620106200-026-G |  |  | CAP,10nF,+/-10%,X7R,16V,G,SMD0402 | SAMSUNG SEMICONDUCTOR | CL05B103KO5NNNC |  |  | PWA BOM |
|  | 620106200-023-G |  |  | CAP,10nF,+/-10%,X7R,16V,G,SMD0402 | TAIYO ELECTRIC IND.CO.LTD | EMK105B7103KV-F |  |  | PWA BOM |
| 2 | 620106205-015-G | 33 | 0 | CAP,10nF,+/-10%,X7R,16V,G,SMD0402 | MURATA ELEC. NORTH AMERICA | GRM155R71C103KA01D |  | (-)C3,C6,C7,C25,C30,C39,C44,C49,C54,C61,C62,C69,C70,C77,C78,C85,C86,C93,C94,C101,C102,C109,C110,C117,C118,C125,C126,C133,C134,C141,C142,C149,C150 | PWA BOM |
|  | 620106200-012-G |  |  | CAP,10nF,+/-10%,X7R,16V,G,SMD0402 | WALSIN | 0402B103K160CT |  |  | PWA BOM |
|  | 620106200-026-G |  |  | CAP,10nF,+/-10%,X7R,16V,G,SMD0402 | SAMSUNG SEMICONDUCTOR | CL05B103KO5NNNC |  |  | PWA BOM |
|  | 620106200-023-G |  |  | CAP,10nF,+/-10%,X7R,16V,G,SMD0402 | TAIYO ELECTRIC IND.CO.LTD | EMK105B7103KV-F |  |  | PWA BOM |
| 3 | 62010L800-015-G | 1 | 0 | CAP,1nF,+/-5%,NPO(C0G),50V,G,SMD0402 | MURATA ELEC. NORTH AMERICA | GRM1555C1H102J |  | (-)PSCC5 | PWA BOM |
|  | 62010L800-026-G |  |  | CAP,1nF,+/-5%,NPO(C0G),50V,G,SMD0402 | SAMSUNG SEMICONDUCTOR | CL05C102JB5NNNC |  |  | PWA BOM |
|  | 62010L800-012-G |  |  | CAP,1nF,+/-5%,NPO(C0G),50V,G,SMD0402 | WALSIN | 0402N102J500CT |  |  | PWA BOM |
| 4 | 61011HA00-017-G | 4 | 3 | RES,1 Ohm,+/-1%,1/16W,G,SMD0402 | KOA SPEER ELECTRONICS, INC. | RK73H1ETTP1R00F |  | (-)PSCR4 | PWA BOM |
|  | 61011HA00-011-G |  |  | RES,1 Ohm,+/-1%,1/16W,G,SMD0402 | YAGEO | RC0402FR-071RL |  |  | PWA BOM |
|  | 61011HA00-012-G |  |  | RES,1 Ohm,+/-1%,1/16W,G,SMD0402 | WALSIN | WR04W1R00FTL |  |  | PWA BOM |
|  | 61011HA00-044-G |  |  | RES,1 Ohm,+/-1%,1/16W,G,SMD0402 | TA-I | RM04FTN1R00 |  |  | PWA BOM |
|  | 61011HA00-029-G |  |  | RES,1 Ohm,+/-1%,1/16W,G,SMD0402 | VISHAY ENTER TECHNO LOGY.INC | CRCW04021R00FNED |  |  | PWA BOM |
| OOOOOOOOOOOOOOOOOOOOOOOOOOOOOOOOOOOOOOOOOOOOOOOOOOOOOOOOOOOOOOOOOOOOOOOOOOOOOOOOOOOOOOOOOO | OOOOOOOOOOOOOOOOOOOOOOOOOOOOOOOOOOOOOOOOOOOOOOOOOOOOOOOOOOOOOOOOOOOOOOOOOOOOOOOOOOOOOOOOOO | OOOOOOOOOOOOOOOOOOOOOOOOOOOOOOOOOOOOOOOOOOOOOOOOOOOOOOOOOOOOOOOOOOOOOOOOOOOOOOOOOOOOOOOOOO | OOOOOOOOOOOOOOOOOOOOOOOOOOOOOOOOOOOOOOOOOOOOOOOOOOOOOOOOOOOOOOOOOOOOOOOOOOOOOOOOOOOOOOOOOO | OOOOOOOOOOOOOOOOOOOOOOOOOOOOOOOOOOOOOOOOOOOOOOOOOOOOOOOOOOOOOOOOOOOOOOOOOOOOOOOOOOOOOOOOOO | OOOOOOOOOOOOOOOOOOOOOOOOOOOOOOOOOOOOOOOOOOOOOOOOOOOOOOOOOOOOOOOOOOOOOOOOOOOOOOOOOOOOOOOOOO | OOOOOOOOOOOOOOOOOOOOOOOOOOOOOOOOOOOOOOOOOOOOOOOOOOOOOOOOOOOOOOOOOOOOOOOOOOOOOOOOOOOOOOOOOO | OOOOOOOOOOOOOOOOOOOOOOOOOOOOOOOOOOOOOOOOOOOOOOOOOOOOOOOOOOOOOOOOOOOOOOOOOOOOOOOOOOOOOOOOOO | OOOOOOOOOOOOOOOOOOOOOOOOOOOOOOOOOOOOOOOOOOOOOOOOOOOOOOOOOOOOOOOOOOOOOOOOOOOOOOOOOOOOOOOOOO |  |
| TLA Parts Change |  |  |  |  |  |  |  |  |  |
| Item | Foxconn P/N | Qty | Part Description | Manufacturer Full Name | Manufacturer P/N | RoHS | Location | Remark |  |
